(kicad_pcb
	(version 20260206)
	(generator "pcbnew")
	(generator_version "10.0")
	(general
		(thickness 1.6)
		(legacy_teardrops no)
	)
	(paper "A4")
	(title_block
		(title "03242023_DA0F0TMBIJ0_F0T_Motherboard_J_brd_V01_OCP.brd")
		(comment 1 "Grand Teton / footprints 951-957 of 6105")
	)
	(layers
		(0 "F.Cu" signal "TOP")
		(4 "In1.Cu" signal "GND")
		(6 "In2.Cu" signal "IN1")
		(8 "In3.Cu" signal "GND1")
		(10 "In4.Cu" signal "IN2")
		(12 "In5.Cu" signal "GND2")
		(14 "In6.Cu" signal "IN3")
		(16 "In7.Cu" signal "GND3")
		(18 "In8.Cu" signal "VCC")
		(20 "In9.Cu" signal "VCC1")
		(22 "In10.Cu" signal "GND4")
		(24 "In11.Cu" signal "IN4")
		(26 "In12.Cu" signal "GND5")
		(28 "In13.Cu" signal "IN5")
		(30 "In14.Cu" signal "GND6")
		(32 "In15.Cu" signal "IN6")
		(34 "In16.Cu" signal "GND7")
		(2 "B.Cu" signal "BOTTOM")
		(9 "F.Adhes" user "F.Adhesive")
		(11 "B.Adhes" user "B.Adhesive")
		(13 "F.Paste" user "Package Geometry/Pastemask Top")
		(15 "B.Paste" user "Package Geometry/Pastemask Bottom")
		(5 "F.SilkS" user "Ref Des/Silkscreen Top")
		(7 "B.SilkS" user "Ref Des/Silkscreen Bottom")
		(1 "F.Mask" user "Board Geometry/Soldermask Top")
		(3 "B.Mask" user "Board Geometry/Soldermask Bottom")
		(17 "Dwgs.User" user "User.Drawings")
		(19 "Cmts.User" user "User.Comments")
		(21 "Eco1.User" user "User.Eco1")
		(23 "Eco2.User" user "User.Eco2")
		(25 "Edge.Cuts" user "Board Geometry/Outline")
		(27 "Margin" user)
		(31 "F.CrtYd" user "Package Geometry/Place Bound Top")
		(29 "B.CrtYd" user "Package Geometry/Place Bound Bottom")
		(35 "F.Fab" user "Ref Des/Assembly Top")
		(33 "B.Fab" user "Ref Des/Assembly Bottom")
	)
	(footprint ""
		(layer "F.Cu")
		(at 40.161972 -434.344318 90)
		(property "Reference" "R2893"
			(at 0 0 90)
			(layer "F.SilkS")
			(hide yes)
			(effects
				(font
					(size 1.27 1.27)
				)
			)
		)
		(property "Value" ""
			(at 0 0 90)
			(layer "F.Fab")
			(effects
				(font
					(size 1.27 1.27)
				)
			)
		)
		(duplicate_pad_numbers_are_jumpers no)
		(fp_line
			(start 0.7874 -0.4064)
			(end 0.7874 0.4064)
			(stroke
				(width 0.1524)
				(type default)
			)
			(layer "F.SilkS")
		)
		(fp_line
			(start -0.7874 -0.4064)
			(end 0.7874 -0.4064)
			(stroke
				(width 0.1524)
				(type default)
			)
			(layer "F.SilkS")
		)
		(fp_line
			(start 0.7874 0.4064)
			(end -0.7874 0.4064)
			(stroke
				(width 0.1524)
				(type default)
			)
			(layer "F.SilkS")
		)
		(fp_line
			(start -0.7874 0.4064)
			(end -0.7874 -0.4064)
			(stroke
				(width 0.1524)
				(type default)
			)
			(layer "F.SilkS")
		)
		(fp_line
			(start -0.12065 -0.305054)
			(end -0.12065 -0.2794)
			(stroke
				(width 0.1)
				(type default)
			)
			(layer "F.Fab")
		)
		(fp_line
			(start -0.67945 -0.305054)
			(end -0.12065 -0.305054)
			(stroke
				(width 0.1)
				(type default)
			)
			(layer "F.Fab")
		)
		(fp_line
			(start 0.67945 -0.3048)
			(end 0.67945 0.3048)
			(stroke
				(width 0.1)
				(type default)
			)
			(layer "F.Fab")
		)
		(fp_line
			(start 0.12065 -0.3048)
			(end 0.67945 -0.3048)
			(stroke
				(width 0.1)
				(type default)
			)
			(layer "F.Fab")
		)
		(fp_line
			(start 0.12065 -0.2794)
			(end 0.12065 -0.3048)
			(stroke
				(width 0.1)
				(type default)
			)
			(layer "F.Fab")
		)
		(fp_line
			(start -0.12065 -0.2794)
			(end 0.12065 -0.2794)
			(stroke
				(width 0.1)
				(type default)
			)
			(layer "F.Fab")
		)
		(fp_line
			(start 0.120396 0.2794)
			(end -0.12065 0.2794)
			(stroke
				(width 0.1)
				(type default)
			)
			(layer "F.Fab")
		)
		(fp_line
			(start -0.12065 0.2794)
			(end -0.12065 0.3048)
			(stroke
				(width 0.1)
				(type default)
			)
			(layer "F.Fab")
		)
		(fp_line
			(start 0.67945 0.3048)
			(end 0.120396 0.3048)
			(stroke
				(width 0.1)
				(type default)
			)
			(layer "F.Fab")
		)
		(fp_line
			(start 0.120396 0.3048)
			(end 0.120396 0.2794)
			(stroke
				(width 0.1)
				(type default)
			)
			(layer "F.Fab")
		)
		(fp_line
			(start -0.12065 0.3048)
			(end -0.67945 0.3048)
			(stroke
				(width 0.1)
				(type default)
			)
			(layer "F.Fab")
		)
		(fp_line
			(start -0.67945 0.3048)
			(end -0.67945 -0.305054)
			(stroke
				(width 0.1)
				(type default)
			)
			(layer "F.Fab")
		)
		(pad "1" smd circle
			(at -0.40005 0 90)
			(size 0 0)
			(layers "F.Cu" "F.Mask" "F.Paste")
			(net "SMB_1_BMC_GPU_R_SCL")
		)
		(pad "2" smd circle
			(at 0.40005 0 90)
			(size 0 0)
			(layers "F.Cu" "F.Mask" "F.Paste")
			(net "SMB_1_BMC_GPU_BUF_R_SCL")
		)
	)
	(footprint ""
		(layer "F.Cu")
		(at 126.256034 -402.371052 -90)
		(property "Reference" "C747"
			(at 0 0 270)
			(layer "F.SilkS")
			(hide yes)
			(effects
				(font
					(size 1.27 1.27)
				)
			)
		)
		(property "Value" ""
			(at 0 0 270)
			(layer "F.Fab")
			(effects
				(font
					(size 1.27 1.27)
				)
			)
		)
		(duplicate_pad_numbers_are_jumpers no)
		(fp_line
			(start -0.299974 0.150114)
			(end -0.299974 -0.150114)
			(stroke
				(width 0.1)
				(type default)
			)
			(layer "F.Fab")
		)
		(fp_line
			(start 0.299974 0.150114)
			(end -0.299974 0.150114)
			(stroke
				(width 0.1)
				(type default)
			)
			(layer "F.Fab")
		)
		(fp_line
			(start -0.299974 -0.150114)
			(end 0.299974 -0.150114)
			(stroke
				(width 0.1)
				(type default)
			)
			(layer "F.Fab")
		)
		(fp_line
			(start 0.299974 -0.150114)
			(end 0.299974 0.150114)
			(stroke
				(width 0.1)
				(type default)
			)
			(layer "F.Fab")
		)
		(pad "1" smd rect
			(at -0.2667 0 270)
			(size 0.3048 0.381)
			(layers "F.Cu" "F.Mask" "F.Paste")
			(net "P5E_CPU1_PE2_TX_C_DP<13>")
		)
		(pad "2" smd rect
			(at 0.2667 0 270)
			(size 0.3048 0.381)
			(layers "F.Cu" "F.Mask" "F.Paste")
			(net "P5E_CPU1_PE2_TX_DP<13>")
		)
	)
	(footprint ""
		(layer "F.Cu")
		(at 322.287138 -13.721588 180)
		(property "Reference" "R1765"
			(at 0 0 180)
			(layer "F.SilkS")
			(hide yes)
			(effects
				(font
					(size 1.27 1.27)
				)
			)
		)
		(property "Value" ""
			(at 0 0 180)
			(layer "F.Fab")
			(effects
				(font
					(size 1.27 1.27)
				)
			)
		)
		(duplicate_pad_numbers_are_jumpers no)
		(fp_line
			(start 1.651 0.8382)
			(end -1.651 0.8382)
			(stroke
				(width 0.1524)
				(type default)
			)
			(layer "F.SilkS")
		)
		(fp_line
			(start 1.651 -0.8382)
			(end 1.651 0.8382)
			(stroke
				(width 0.1524)
				(type default)
			)
			(layer "F.SilkS")
		)
		(fp_line
			(start -1.651 0.8382)
			(end -1.651 -0.8382)
			(stroke
				(width 0.1524)
				(type default)
			)
			(layer "F.SilkS")
		)
		(fp_line
			(start -1.651 -0.8382)
			(end 1.651 -0.8382)
			(stroke
				(width 0.1524)
				(type default)
			)
			(layer "F.SilkS")
		)
		(fp_line
			(start 1.560576 0.7366)
			(end 1.560576 -0.7366)
			(stroke
				(width 0.1)
				(type default)
			)
			(layer "F.Fab")
		)
		(fp_line
			(start 1.560576 -0.7366)
			(end 1.524 -0.7366)
			(stroke
				(width 0.1)
				(type default)
			)
			(layer "F.Fab")
		)
		(fp_line
			(start 1.524 0.7366)
			(end 1.560576 0.7366)
			(stroke
				(width 0.1)
				(type default)
			)
			(layer "F.Fab")
		)
		(fp_line
			(start 1.524 -0.7366)
			(end -1.524 -0.7366)
			(stroke
				(width 0.1)
				(type default)
			)
			(layer "F.Fab")
		)
		(fp_line
			(start -1.524 0.7366)
			(end 1.524 0.7366)
			(stroke
				(width 0.1)
				(type default)
			)
			(layer "F.Fab")
		)
		(fp_line
			(start -1.524 -0.7366)
			(end -1.559814 -0.7366)
			(stroke
				(width 0.1)
				(type default)
			)
			(layer "F.Fab")
		)
		(fp_line
			(start -1.559814 0.7366)
			(end -1.524 0.7366)
			(stroke
				(width 0.1)
				(type default)
			)
			(layer "F.Fab")
		)
		(fp_line
			(start -1.559814 -0.7366)
			(end -1.559814 0.7366)
			(stroke
				(width 0.1)
				(type default)
			)
			(layer "F.Fab")
		)
		(pad "1" smd rect
			(at -0.94996 0)
			(size 1.1176 1.3716)
			(layers "F.Cu" "F.Mask" "F.Paste")
			(net "PGPPA_AUX")
		)
		(pad "2" smd rect
			(at 0.94996 0)
			(size 1.1176 1.3716)
			(layers "F.Cu" "F.Mask" "F.Paste")
			(net "P3V3_AUX")
		)
	)
	(footprint ""
		(layer "F.Cu")
		(at 461.593946 -105.011728 180)
		(property "Reference" "R4762"
			(at 0 0 180)
			(layer "F.SilkS")
			(hide yes)
			(effects
				(font
					(size 1.27 1.27)
				)
			)
		)
		(property "Value" ""
			(at 0 0 180)
			(layer "F.Fab")
			(effects
				(font
					(size 1.27 1.27)
				)
			)
		)
		(duplicate_pad_numbers_are_jumpers no)
		(fp_line
			(start 0.7874 0.4064)
			(end -0.7874 0.4064)
			(stroke
				(width 0.1524)
				(type default)
			)
			(layer "F.SilkS")
		)
		(fp_line
			(start 0.7874 -0.4064)
			(end 0.7874 0.4064)
			(stroke
				(width 0.1524)
				(type default)
			)
			(layer "F.SilkS")
		)
		(fp_line
			(start -0.7874 0.4064)
			(end -0.7874 -0.4064)
			(stroke
				(width 0.1524)
				(type default)
			)
			(layer "F.SilkS")
		)
		(fp_line
			(start -0.7874 -0.4064)
			(end 0.7874 -0.4064)
			(stroke
				(width 0.1524)
				(type default)
			)
			(layer "F.SilkS")
		)
		(fp_line
			(start 0.67945 0.3048)
			(end 0.120396 0.3048)
			(stroke
				(width 0.1)
				(type default)
			)
			(layer "F.Fab")
		)
		(fp_line
			(start 0.67945 -0.3048)
			(end 0.67945 0.3048)
			(stroke
				(width 0.1)
				(type default)
			)
			(layer "F.Fab")
		)
		(fp_line
			(start 0.12065 -0.2794)
			(end 0.12065 -0.3048)
			(stroke
				(width 0.1)
				(type default)
			)
			(layer "F.Fab")
		)
		(fp_line
			(start 0.12065 -0.3048)
			(end 0.67945 -0.3048)
			(stroke
				(width 0.1)
				(type default)
			)
			(layer "F.Fab")
		)
		(fp_line
			(start 0.120396 0.3048)
			(end 0.120396 0.2794)
			(stroke
				(width 0.1)
				(type default)
			)
			(layer "F.Fab")
		)
		(fp_line
			(start 0.120396 0.2794)
			(end -0.12065 0.2794)
			(stroke
				(width 0.1)
				(type default)
			)
			(layer "F.Fab")
		)
		(fp_line
			(start -0.12065 0.3048)
			(end -0.67945 0.3048)
			(stroke
				(width 0.1)
				(type default)
			)
			(layer "F.Fab")
		)
		(fp_line
			(start -0.12065 0.2794)
			(end -0.12065 0.3048)
			(stroke
				(width 0.1)
				(type default)
			)
			(layer "F.Fab")
		)
		(fp_line
			(start -0.12065 -0.2794)
			(end 0.12065 -0.2794)
			(stroke
				(width 0.1)
				(type default)
			)
			(layer "F.Fab")
		)
		(fp_line
			(start -0.12065 -0.305054)
			(end -0.12065 -0.2794)
			(stroke
				(width 0.1)
				(type default)
			)
			(layer "F.Fab")
		)
		(fp_line
			(start -0.67945 0.3048)
			(end -0.67945 -0.305054)
			(stroke
				(width 0.1)
				(type default)
			)
			(layer "F.Fab")
		)
		(fp_line
			(start -0.67945 -0.305054)
			(end -0.12065 -0.305054)
			(stroke
				(width 0.1)
				(type default)
			)
			(layer "F.Fab")
		)
		(pad "1" smd circle
			(at -0.40005 0 180)
			(size 0 0)
			(layers "F.Cu" "F.Mask" "F.Paste")
			(net "P3V3_AUX")
		)
		(pad "2" smd circle
			(at 0.40005 0 180)
			(size 0 0)
			(layers "F.Cu" "F.Mask" "F.Paste")
			(net "HP_LVC3_OCP_V3_1_PRSNT2_PLD_N")
		)
	)
	(footprint ""
		(layer "F.Cu")
		(at 56.341518 -408.517344 -90)
		(property "Reference" "C705"
			(at 0 0 270)
			(layer "F.SilkS")
			(hide yes)
			(effects
				(font
					(size 1.27 1.27)
				)
			)
		)
		(property "Value" ""
			(at 0 0 270)
			(layer "F.Fab")
			(effects
				(font
					(size 1.27 1.27)
				)
			)
		)
		(duplicate_pad_numbers_are_jumpers no)
		(fp_line
			(start -0.299974 0.150114)
			(end -0.299974 -0.150114)
			(stroke
				(width 0.1)
				(type default)
			)
			(layer "F.Fab")
		)
		(fp_line
			(start 0.299974 0.150114)
			(end -0.299974 0.150114)
			(stroke
				(width 0.1)
				(type default)
			)
			(layer "F.Fab")
		)
		(fp_line
			(start -0.299974 -0.150114)
			(end 0.299974 -0.150114)
			(stroke
				(width 0.1)
				(type default)
			)
			(layer "F.Fab")
		)
		(fp_line
			(start 0.299974 -0.150114)
			(end 0.299974 0.150114)
			(stroke
				(width 0.1)
				(type default)
			)
			(layer "F.Fab")
		)
		(pad "1" smd rect
			(at -0.2667 0 270)
			(size 0.3048 0.381)
			(layers "F.Cu" "F.Mask" "F.Paste")
			(net "P5E_CPU1_PE4_TX_C_DP<2>")
		)
		(pad "2" smd rect
			(at 0.2667 0 270)
			(size 0.3048 0.381)
			(layers "F.Cu" "F.Mask" "F.Paste")
			(net "P5E_CPU1_PE4_TX_DP<2>")
		)
	)
	(footprint ""
		(layer "F.Cu")
		(at 120.36044 -427.091348 180)
		(property "Reference" "R3506"
			(at 0 0 180)
			(layer "F.SilkS")
			(hide yes)
			(effects
				(font
					(size 1.27 1.27)
				)
			)
		)
		(property "Value" ""
			(at 0 0 180)
			(layer "F.Fab")
			(effects
				(font
					(size 1.27 1.27)
				)
			)
		)
		(duplicate_pad_numbers_are_jumpers no)
		(fp_line
			(start 0.7874 0.4064)
			(end -0.7874 0.4064)
			(stroke
				(width 0.1524)
				(type default)
			)
			(layer "F.SilkS")
		)
		(fp_line
			(start 0.7874 -0.4064)
			(end 0.7874 0.4064)
			(stroke
				(width 0.1524)
				(type default)
			)
			(layer "F.SilkS")
		)
		(fp_line
			(start -0.7874 0.4064)
			(end -0.7874 -0.4064)
			(stroke
				(width 0.1524)
				(type default)
			)
			(layer "F.SilkS")
		)
		(fp_line
			(start -0.7874 -0.4064)
			(end 0.7874 -0.4064)
			(stroke
				(width 0.1524)
				(type default)
			)
			(layer "F.SilkS")
		)
		(fp_line
			(start 0.67945 0.3048)
			(end 0.120396 0.3048)
			(stroke
				(width 0.1)
				(type default)
			)
			(layer "F.Fab")
		)
		(fp_line
			(start 0.67945 -0.3048)
			(end 0.67945 0.3048)
			(stroke
				(width 0.1)
				(type default)
			)
			(layer "F.Fab")
		)
		(fp_line
			(start 0.12065 -0.2794)
			(end 0.12065 -0.3048)
			(stroke
				(width 0.1)
				(type default)
			)
			(layer "F.Fab")
		)
		(fp_line
			(start 0.12065 -0.3048)
			(end 0.67945 -0.3048)
			(stroke
				(width 0.1)
				(type default)
			)
			(layer "F.Fab")
		)
		(fp_line
			(start 0.120396 0.3048)
			(end 0.120396 0.2794)
			(stroke
				(width 0.1)
				(type default)
			)
			(layer "F.Fab")
		)
		(fp_line
			(start 0.120396 0.2794)
			(end -0.12065 0.2794)
			(stroke
				(width 0.1)
				(type default)
			)
			(layer "F.Fab")
		)
		(fp_line
			(start -0.12065 0.3048)
			(end -0.67945 0.3048)
			(stroke
				(width 0.1)
				(type default)
			)
			(layer "F.Fab")
		)
		(fp_line
			(start -0.12065 0.2794)
			(end -0.12065 0.3048)
			(stroke
				(width 0.1)
				(type default)
			)
			(layer "F.Fab")
		)
		(fp_line
			(start -0.12065 -0.2794)
			(end 0.12065 -0.2794)
			(stroke
				(width 0.1)
				(type default)
			)
			(layer "F.Fab")
		)
		(fp_line
			(start -0.12065 -0.305054)
			(end -0.12065 -0.2794)
			(stroke
				(width 0.1)
				(type default)
			)
			(layer "F.Fab")
		)
		(fp_line
			(start -0.67945 0.3048)
			(end -0.67945 -0.305054)
			(stroke
				(width 0.1)
				(type default)
			)
			(layer "F.Fab")
		)
		(fp_line
			(start -0.67945 -0.305054)
			(end -0.12065 -0.305054)
			(stroke
				(width 0.1)
				(type default)
			)
			(layer "F.Fab")
		)
		(pad "1" smd circle
			(at -0.40005 0 180)
			(size 0 0)
			(layers "F.Cu" "F.Mask" "F.Paste")
			(net "P3V3_AUX")
		)
		(pad "2" smd circle
			(at 0.40005 0 180)
			(size 0 0)
			(layers "F.Cu" "F.Mask" "F.Paste")
			(net "GPU_FPGA_RST_R_N")
		)
	)
	(footprint ""
		(layer "F.Cu")
		(at 359.774998 -431.359818 180)
		(property "Reference" "J123"
			(at -0.529082 -11.63828 0)
			(unlocked yes)
			(layer "F.SilkS")
			(effects
				(font
					(size 0.7874 0.5842)
					(thickness 0.1524)
				)
				(justify left)
			)
		)
		(property "Value" ""
			(at 0 0 180)
			(layer "F.Fab")
			(effects
				(font
					(size 1.27 1.27)
				)
			)
		)
		(duplicate_pad_numbers_are_jumpers no)
		(fp_line
			(start 3.525012 21.310092)
			(end 3.525012 -10.489946)
			(stroke
				(width 0.1524)
				(type default)
			)
			(layer "F.SilkS")
		)
		(fp_line
			(start 3.525012 -10.489946)
			(end -3.525012 -10.489946)
			(stroke
				(width 0.1524)
				(type default)
			)
			(layer "F.SilkS")
		)
		(fp_line
			(start -3.525012 21.310092)
			(end 3.525012 21.310092)
			(stroke
				(width 0.1524)
				(type default)
			)
			(layer "F.SilkS")
		)
		(fp_line
			(start -3.525012 10.6299)
			(end 3.525012 10.6299)
			(stroke
				(width 0.1524)
				(type default)
			)
			(layer "F.SilkS")
		)
		(fp_line
			(start -3.525012 -10.489946)
			(end -3.525012 21.310092)
			(stroke
				(width 0.1524)
				(type default)
			)
			(layer "F.SilkS")
		)
		(fp_line
			(start 3.525012 21.310092)
			(end 3.525012 -10.489946)
			(stroke
				(width 0.1)
				(type default)
			)
			(layer "F.Fab")
		)
		(fp_line
			(start 3.525012 -10.489946)
			(end -3.525012 -10.489946)
			(stroke
				(width 0.1)
				(type default)
			)
			(layer "F.Fab")
		)
		(fp_line
			(start -3.525012 21.310092)
			(end 3.525012 21.310092)
			(stroke
				(width 0.1)
				(type default)
			)
			(layer "F.Fab")
		)
		(fp_line
			(start -3.525012 -10.489946)
			(end -3.525012 21.310092)
			(stroke
				(width 0.1)
				(type default)
			)
			(layer "F.Fab")
		)
		(pad "" np_thru_hole circle
			(at 0 -6.620002 180)
			(size 3.175 3.175)
			(drill 3.175)
			(layers "*.Cu" "*.Mask")
			(clearance 0.381)
			(thermal_gap 0.381)
		)
		(pad "" np_thru_hole circle
			(at 0 0 180)
			(size 0 0)
			(drill 3.175)
			(layers "*.Cu" "*.Mask")
			(clearance 0)
		)
		(pad "" np_thru_hole circle
			(at 0 5.130038 180)
			(size 3.175 3.175)
			(drill 3.175)
			(layers "*.Cu" "*.Mask")
			(clearance 0.381)
			(thermal_gap 0.381)
		)
		(zone
			(layers "F.Cu" "B.Cu" "In1.Cu" "In2.Cu" "In3.Cu" "In4.Cu" "In5.Cu" "In6.Cu"
				"In7.Cu" "In8.Cu" "In9.Cu" "In10.Cu" "In11.Cu" "In12.Cu" "In13.Cu" "In14.Cu"
				"In15.Cu" "In16.Cu"
			)
			(hatch none 0.5)
			(connect_pads
				(clearance 0)
			)
			(min_thickness 0.25)
			(keepout
				(tracks not_allowed)
				(vias allowed)
				(pads allowed)
				(copperpour not_allowed)
				(footprints allowed)
			)
			(placement
				(enabled no)
				(sheetname "")
			)
			(fill
				(thermal_gap 0.5)
				(thermal_bridge_width 0.5)
				(island_removal_mode 0)
			)
			(polygon
				(pts
					(arc
						(start 361.870498 -436.489856)
						(mid 357.679498 -436.489856)
						(end 361.870498 -436.489856)
					)
				)
			)
		)
		(zone
			(layers "F.Cu" "B.Cu" "In1.Cu" "In2.Cu" "In3.Cu" "In4.Cu" "In5.Cu" "In6.Cu"
				"In7.Cu" "In8.Cu" "In9.Cu" "In10.Cu" "In11.Cu" "In12.Cu" "In13.Cu" "In14.Cu"
				"In15.Cu" "In16.Cu"
			)
			(hatch none 0.5)
			(connect_pads
				(clearance 0)
			)
			(min_thickness 0.25)
			(keepout
				(tracks not_allowed)
				(vias allowed)
				(pads allowed)
				(copperpour not_allowed)
				(footprints allowed)
			)
			(placement
				(enabled no)
				(sheetname "")
			)
			(fill
				(thermal_gap 0.5)
				(thermal_bridge_width 0.5)
				(island_removal_mode 0)
			)
			(polygon
				(pts
					(arc
						(start 361.870498 -424.739816)
						(mid 357.679498 -424.739816)
						(end 361.870498 -424.739816)
					)
				)
			)
		)
		(zone
			(layers "F.Cu" "B.Cu" "In1.Cu" "In2.Cu" "In3.Cu" "In4.Cu" "In5.Cu" "In6.Cu"
				"In7.Cu" "In8.Cu" "In9.Cu" "In10.Cu" "In11.Cu" "In12.Cu" "In13.Cu" "In14.Cu"
				"In15.Cu" "In16.Cu"
			)
			(hatch none 0.5)
			(connect_pads
				(clearance 0)
			)
			(min_thickness 0.25)
			(keepout
				(tracks not_allowed)
				(vias allowed)
				(pads allowed)
				(copperpour not_allowed)
				(footprints allowed)
			)
			(placement
				(enabled no)
				(sheetname "")
			)
			(fill
				(thermal_gap 0.5)
				(thermal_bridge_width 0.5)
				(island_removal_mode 0)
			)
			(polygon
				(pts
					(arc
						(start 363.394498 -431.359818)
						(mid 356.155498 -431.359818)
						(end 363.394498 -431.359818)
					)
				)
			)
		)
	)
)
